# BASEBOARD_FAB2 (Tioga Pass) — schematic netlist excerpt (pin names and nets, part order shuffled) for the footprints in the layout excerpt that follows; sources: Cadence DE-HDL packaged netlist, KiCad conversion of Wiwynn_Tioga_Pass_MB.brd

C5G43  CAP_A  22.0UF 4V 20% X6S  pkg 0603V  page 242 : A = PVDDQ_ABC ; B = GND
R3L6  RES  0.0 5% CHIP  pkg 0402  page 219 : A = VR_PVDDQ_DEF_PH1_VCIN ; B = P5V_STBY
C9G12  CAP  4700PF 50V 10% EMPTY  pkg 0402LF  page 141 : A = NIC_SER_N_MDI_3_DN ; B = NIC_MDI_MNG_RX_DN

(kicad_pcb
	(version 20260206)
	(generator "pcbnew")
	(generator_version "10.0")
	(general
		(thickness 1.6)
		(legacy_teardrops no)
	)
	(paper "A4")
	(title_block
		(title "Wiwynn_Tioga_Pass_MB.brd")
		(comment 1 "Tioga Pass / footprints 3715-3717 of 4770")
	)
	(layers
		(0 "F.Cu" signal "TOP")
		(4 "In1.Cu" signal "L2GND")
		(6 "In2.Cu" signal "L3")
		(8 "In3.Cu" signal "L4GND")
		(10 "In4.Cu" signal "L5")
		(12 "In5.Cu" signal "L6GND")
		(14 "In6.Cu" signal "L7VCC")
		(16 "In7.Cu" signal "L8VCC")
		(18 "In8.Cu" signal "L9GND")
		(20 "In9.Cu" signal "L10")
		(22 "In10.Cu" signal "L11GND")
		(24 "In11.Cu" signal "L12")
		(26 "In12.Cu" signal "L13GND")
		(2 "B.Cu" signal "BOTTOM")
		(9 "F.Adhes" user "F.Adhesive")
		(11 "B.Adhes" user "B.Adhesive")
		(13 "F.Paste" user "Package Geometry/Pastemask Top")
		(15 "B.Paste" user "Package Geometry/Pastemask Bottom")
		(5 "F.SilkS" user "Ref Des/Silkscreen Top")
		(7 "B.SilkS" user "Ref Des/Silkscreen Bottom")
		(1 "F.Mask" user "Board Geometry/Soldermask Top")
		(3 "B.Mask" user "Board Geometry/Soldermask Bottom")
		(17 "Dwgs.User" user "User.Drawings")
		(19 "Cmts.User" user "User.Comments")
		(21 "Eco1.User" user "User.Eco1")
		(23 "Eco2.User" user "User.Eco2")
		(25 "Edge.Cuts" user "Board Geometry/Outline")
		(27 "Margin" user)
		(31 "F.CrtYd" user "Package Geometry/Place Bound Top")
		(29 "B.CrtYd" user "Package Geometry/Place Bound Bottom")
		(35 "F.Fab" user "Ref Des/Assembly Top")
		(33 "B.Fab" user "Ref Des/Assembly Bottom")
	)
	(footprint ""
		(layer "B.Cu")
		(at 252.1585 -12.954 -90)
		(property "Reference" "C5G43"
			(at -1.14681 0.76708 0)
			(unlocked yes)
			(layer "B.SilkS")
			(effects
				(font
					(size 0.7874 0.5842)
					(thickness 0.1524)
				)
				(justify mirror)
			)
		)
		(property "Value" ""
			(at 0 0 90)
			(layer "B.Fab")
			(effects
				(font
					(size 1.27 1.27)
				)
				(justify mirror)
			)
		)
		(duplicate_pad_numbers_are_jumpers no)
		(fp_rect
			(start 0.4953 1.6002)
			(end -0.4953 -0.2032)
			(stroke
				(width 0)
				(type default)
			)
			(fill no)
			(layer "B.CrtYd")
		)
		(fp_line
			(start -0.4953 1.6002)
			(end 0.4953 1.6002)
			(stroke
				(width 0.1)
				(type default)
			)
			(layer "B.Fab")
		)
		(fp_line
			(start 0.4953 1.6002)
			(end 0.4953 -0.2032)
			(stroke
				(width 0.1)
				(type default)
			)
			(layer "B.Fab")
		)
		(fp_line
			(start -0.4953 -0.2032)
			(end -0.4953 1.6002)
			(stroke
				(width 0.1)
				(type default)
			)
			(layer "B.Fab")
		)
		(fp_line
			(start 0.4953 -0.2032)
			(end -0.4953 -0.2032)
			(stroke
				(width 0.1)
				(type default)
			)
			(layer "B.Fab")
		)
		(pad "1" smd rect
			(at 0 0 90)
			(size 0.762 0.889)
			(layers "B.Cu" "B.Mask" "B.Paste")
			(net "PVDDQ_ABC")
		)
		(pad "2" smd rect
			(at 0 1.397 90)
			(size 0.762 0.889)
			(layers "B.Cu" "B.Mask" "B.Paste")
			(net "GND")
		)
		(zone
			(layer "B.Cu")
			(hatch none 0.5)
			(connect_pads
				(clearance 0)
			)
			(min_thickness 0.25)
			(keepout
				(tracks not_allowed)
				(vias allowed)
				(pads allowed)
				(copperpour not_allowed)
				(footprints allowed)
			)
			(placement
				(enabled no)
				(sheetname "")
			)
			(fill
				(thermal_gap 0.5)
				(thermal_bridge_width 0.5)
				(island_removal_mode 0)
			)
			(polygon
				(pts
					(xy 251.206 -12.573) (xy 251.714 -12.573) (xy 251.714 -13.335) (xy 251.206 -13.335)
				)
			)
		)
	)
	(footprint ""
		(layer "B.Cu")
		(at 349.0214 -155.7274 -90)
		(property "Reference" "R3L6"
			(at 0 0 90)
			(layer "B.SilkS")
			(hide yes)
			(effects
				(font
					(size 1.27 1.27)
				)
				(justify mirror)
			)
		)
		(property "Value" ""
			(at 0 0 90)
			(layer "B.Fab")
			(effects
				(font
					(size 1.27 1.27)
				)
				(justify mirror)
			)
		)
		(duplicate_pad_numbers_are_jumpers no)
		(fp_poly
			(pts
				(xy 0.2794 -0.1016) (xy -0.2794 -0.1016) (xy -0.2794 0.9906) (xy 0.2794 0.9906)
			)
			(stroke
				(width 0)
				(type default)
			)
			(fill no)
			(layer "B.CrtYd")
		)
		(fp_line
			(start -0.2794 0.9906)
			(end -0.2794 -0.1016)
			(stroke
				(width 0.1)
				(type default)
			)
			(layer "B.Fab")
		)
		(fp_line
			(start 0.2794 0.9906)
			(end -0.2794 0.9906)
			(stroke
				(width 0.1)
				(type default)
			)
			(layer "B.Fab")
		)
		(fp_line
			(start -0.2794 -0.1016)
			(end 0.2794 -0.1016)
			(stroke
				(width 0.1)
				(type default)
			)
			(layer "B.Fab")
		)
		(fp_line
			(start 0.2794 -0.1016)
			(end 0.2794 0.9906)
			(stroke
				(width 0.1)
				(type default)
			)
			(layer "B.Fab")
		)
		(pad "1" smd rect
			(at 0 0 90)
			(size 0.508 0.508)
			(layers "B.Cu" "B.Mask" "B.Paste")
			(net "VR_PVDDQ_DEF_PH1_VCIN")
		)
		(pad "2" smd rect
			(at 0 0.889 90)
			(size 0.508 0.508)
			(layers "B.Cu" "B.Mask" "B.Paste")
			(net "P5V_STBY")
		)
		(zone
			(layer "B.Cu")
			(hatch none 0.5)
			(connect_pads
				(clearance 0)
			)
			(min_thickness 0.25)
			(keepout
				(tracks not_allowed)
				(vias allowed)
				(pads allowed)
				(copperpour not_allowed)
				(footprints allowed)
			)
			(placement
				(enabled no)
				(sheetname "")
			)
			(fill
				(thermal_gap 0.5)
				(thermal_bridge_width 0.5)
				(island_removal_mode 0)
			)
			(polygon
				(pts
					(xy 348.3864 -155.4734) (xy 348.3864 -155.9814) (xy 348.7674 -155.9814) (xy 348.7674 -155.4734)
				)
			)
		)
		(zone
			(layer "B.Cu")
			(hatch none 0.5)
			(connect_pads
				(clearance 0)
			)
			(min_thickness 0.25)
			(keepout
				(tracks allowed)
				(vias not_allowed)
				(pads allowed)
				(copperpour not_allowed)
				(footprints allowed)
			)
			(placement
				(enabled no)
				(sheetname "")
			)
			(fill
				(thermal_gap 0.5)
				(thermal_bridge_width 0.5)
				(island_removal_mode 0)
			)
			(polygon
				(pts
					(xy 348.7674 -155.4734) (xy 348.7674 -155.9814) (xy 348.3864 -155.9814) (xy 348.3864 -155.4734)
				)
			)
		)
	)
	(footprint ""
		(layer "B.Cu")
		(at 477.634554 -2.513838 -90)
		(property "Reference" "C9G12"
			(at 0 0 90)
			(layer "B.SilkS")
			(hide yes)
			(effects
				(font
					(size 1.27 1.27)
				)
				(justify mirror)
			)
		)
		(property "Value" ""
			(at 0 0 90)
			(layer "B.Fab")
			(effects
				(font
					(size 1.27 1.27)
				)
				(justify mirror)
			)
		)
		(duplicate_pad_numbers_are_jumpers no)
		(fp_poly
			(pts
				(xy -0.3048 -0.1016) (xy -0.3048 0.9906) (xy 0.3048 0.9906) (xy 0.3048 -0.1016)
			)
			(stroke
				(width 0)
				(type default)
			)
			(fill no)
			(layer "B.CrtYd")
		)
		(fp_line
			(start -0.3048 0.9906)
			(end -0.3048 -0.1016)
			(stroke
				(width 0.1)
				(type default)
			)
			(layer "B.Fab")
		)
		(fp_line
			(start 0.3048 0.9906)
			(end -0.3048 0.9906)
			(stroke
				(width 0.1)
				(type default)
			)
			(layer "B.Fab")
		)
		(fp_line
			(start -0.3048 -0.1016)
			(end 0.3048 -0.1016)
			(stroke
				(width 0.1)
				(type default)
			)
			(layer "B.Fab")
		)
		(fp_line
			(start 0.3048 -0.1016)
			(end 0.3048 0.9906)
			(stroke
				(width 0.1)
				(type default)
			)
			(layer "B.Fab")
		)
		(pad "1" smd rect
			(at 0 0 90)
			(size 0.508 0.508)
			(layers "B.Cu" "B.Mask" "B.Paste")
			(net "NIC_SER_N_MDI_3_DN")
		)
		(pad "2" smd rect
			(at 0 0.889 90)
			(size 0.508 0.508)
			(layers "B.Cu" "B.Mask" "B.Paste")
			(net "NIC_MDI_MNG_RX_DN")
		)
		(zone
			(layer "B.Cu")
			(hatch none 0.5)
			(connect_pads
				(clearance 0)
			)
			(min_thickness 0.25)
			(keepout
				(tracks not_allowed)
				(vias allowed)
				(pads allowed)
				(copperpour not_allowed)
				(footprints allowed)
			)
			(placement
				(enabled no)
				(sheetname "")
			)
			(fill
				(thermal_gap 0.5)
				(thermal_bridge_width 0.5)
				(island_removal_mode 0)
			)
			(polygon
				(pts
					(xy 476.999554 -2.259838) (xy 476.999554 -2.767838) (xy 477.380554 -2.767838) (xy 477.380554 -2.259838)
				)
			)
		)
		(zone
			(layer "B.Cu")
			(hatch none 0.5)
			(connect_pads
				(clearance 0)
			)
			(min_thickness 0.25)
			(keepout
				(tracks allowed)
				(vias not_allowed)
				(pads allowed)
				(copperpour not_allowed)
				(footprints allowed)
			)
			(placement
				(enabled no)
				(sheetname "")
			)
			(fill
				(thermal_gap 0.5)
				(thermal_bridge_width 0.5)
				(island_removal_mode 0)
			)
			(polygon
				(pts
					(xy 477.380554 -2.259838) (xy 477.380554 -2.767838) (xy 476.999554 -2.767838) (xy 476.999554 -2.259838)
				)
			)
		)
	)
)
